(kicad_pcb
	(version 20260206)
	(generator "pcbnew")
	(generator_version "10.0")
	(general
		(thickness 1.6)
		(legacy_teardrops no)
	)
	(paper "A4")
	(title_block
		(title "01162023_DA0F0TEBIF0_F0T_Expander_BD_F_brd_V02_OCP.brd")
		(comment 1 "Grand Teton / footprints 6782-6787 of 9728")
	)
	(layers
		(0 "F.Cu" signal "TOP")
		(4 "In1.Cu" signal "GND")
		(6 "In2.Cu" signal "VCC")
		(8 "In3.Cu" signal "VCC1")
		(10 "In4.Cu" signal "GND1")
		(12 "In5.Cu" signal "IN1")
		(14 "In6.Cu" signal "GND2")
		(16 "In7.Cu" signal "IN2")
		(18 "In8.Cu" signal "GND3")
		(20 "In9.Cu" signal "IN3")
		(22 "In10.Cu" signal "GND4")
		(24 "In11.Cu" signal "IN4")
		(26 "In12.Cu" signal "GND5")
		(28 "In13.Cu" signal "IN5")
		(30 "In14.Cu" signal "GND6")
		(32 "In15.Cu" signal "IN6")
		(34 "In16.Cu" signal "GND7")
		(2 "B.Cu" signal "BOTTOM")
		(9 "F.Adhes" user "F.Adhesive")
		(11 "B.Adhes" user "B.Adhesive")
		(13 "F.Paste" user "Package Geometry/Pastemask Top")
		(15 "B.Paste" user "Package Geometry/Pastemask Bottom")
		(5 "F.SilkS" user "Ref Des/Silkscreen Top")
		(7 "B.SilkS" user "Ref Des/Silkscreen Bottom")
		(1 "F.Mask" user "Board Geometry/Soldermask Top")
		(3 "B.Mask" user "Board Geometry/Soldermask Bottom")
		(17 "Dwgs.User" user "User.Drawings")
		(19 "Cmts.User" user "User.Comments")
		(21 "Eco1.User" user "User.Eco1")
		(23 "Eco2.User" user "User.Eco2")
		(25 "Edge.Cuts" user "Board Geometry/Outline")
		(27 "Margin" user)
		(31 "F.CrtYd" user "Package Geometry/Place Bound Top")
		(29 "B.CrtYd" user "Package Geometry/Place Bound Bottom")
		(35 "F.Fab" user "Ref Des/Assembly Top")
		(33 "B.Fab" user "Ref Des/Assembly Bottom")
	)
	(footprint ""
		(layer "F.Cu")
		(at 278.634444 -30.03169 180)
		(property "Reference" "C500"
			(at 0 0 180)
			(layer "F.SilkS")
			(hide yes)
			(effects
				(font
					(size 1.27 1.27)
				)
			)
		)
		(property "Value" ""
			(at 0 0 180)
			(layer "F.Fab")
			(effects
				(font
					(size 1.27 1.27)
				)
			)
		)
		(duplicate_pad_numbers_are_jumpers no)
		(fp_line
			(start 0.299974 0.150114)
			(end -0.299974 0.150114)
			(stroke
				(width 0.1)
				(type default)
			)
			(layer "F.Fab")
		)
		(fp_line
			(start 0.299974 -0.150114)
			(end 0.299974 0.150114)
			(stroke
				(width 0.1)
				(type default)
			)
			(layer "F.Fab")
		)
		(fp_line
			(start -0.299974 0.150114)
			(end -0.299974 -0.150114)
			(stroke
				(width 0.1)
				(type default)
			)
			(layer "F.Fab")
		)
		(fp_line
			(start -0.299974 -0.150114)
			(end 0.299974 -0.150114)
			(stroke
				(width 0.1)
				(type default)
			)
			(layer "F.Fab")
		)
		(pad "1" smd rect
			(at -0.2667 0 180)
			(size 0.3048 0.381)
			(layers "F.Cu" "F.Mask" "F.Paste")
			(net "P5E_PEX2_STN2_TX_DN<41>")
		)
		(pad "2" smd rect
			(at 0.2667 0 180)
			(size 0.3048 0.381)
			(layers "F.Cu" "F.Mask" "F.Paste")
			(net "P5E_PEX2_STN2_TX_C_DN<41>")
		)
	)
	(footprint ""
		(layer "F.Cu")
		(at 324.395846 -103.259128)
		(property "Reference" "C617"
			(at 0 0 0)
			(layer "F.SilkS")
			(hide yes)
			(effects
				(font
					(size 1.27 1.27)
				)
			)
		)
		(property "Value" ""
			(at 0 0 0)
			(layer "F.Fab")
			(effects
				(font
					(size 1.27 1.27)
				)
			)
		)
		(duplicate_pad_numbers_are_jumpers no)
		(fp_line
			(start -0.7874 -0.4064)
			(end 0.7874 -0.4064)
			(stroke
				(width 0.1524)
				(type default)
			)
			(layer "F.SilkS")
		)
		(fp_line
			(start -0.7874 0.4064)
			(end -0.7874 -0.4064)
			(stroke
				(width 0.1524)
				(type default)
			)
			(layer "F.SilkS")
		)
		(fp_line
			(start 0.7874 -0.4064)
			(end 0.7874 0.4064)
			(stroke
				(width 0.1524)
				(type default)
			)
			(layer "F.SilkS")
		)
		(fp_line
			(start 0.7874 0.4064)
			(end -0.7874 0.4064)
			(stroke
				(width 0.1524)
				(type default)
			)
			(layer "F.SilkS")
		)
		(fp_line
			(start -0.67945 -0.305054)
			(end -0.12065 -0.305054)
			(stroke
				(width 0.1)
				(type default)
			)
			(layer "F.Fab")
		)
		(fp_line
			(start -0.67945 0.3048)
			(end -0.67945 -0.305054)
			(stroke
				(width 0.1)
				(type default)
			)
			(layer "F.Fab")
		)
		(fp_line
			(start -0.12065 -0.305054)
			(end -0.12065 -0.2794)
			(stroke
				(width 0.1)
				(type default)
			)
			(layer "F.Fab")
		)
		(fp_line
			(start -0.12065 -0.2794)
			(end 0.12065 -0.2794)
			(stroke
				(width 0.1)
				(type default)
			)
			(layer "F.Fab")
		)
		(fp_line
			(start -0.12065 0.2794)
			(end -0.12065 0.3048)
			(stroke
				(width 0.1)
				(type default)
			)
			(layer "F.Fab")
		)
		(fp_line
			(start -0.12065 0.3048)
			(end -0.67945 0.3048)
			(stroke
				(width 0.1)
				(type default)
			)
			(layer "F.Fab")
		)
		(fp_line
			(start 0.120396 0.2794)
			(end -0.12065 0.2794)
			(stroke
				(width 0.1)
				(type default)
			)
			(layer "F.Fab")
		)
		(fp_line
			(start 0.120396 0.3048)
			(end 0.120396 0.2794)
			(stroke
				(width 0.1)
				(type default)
			)
			(layer "F.Fab")
		)
		(fp_line
			(start 0.12065 -0.3048)
			(end 0.67945 -0.3048)
			(stroke
				(width 0.1)
				(type default)
			)
			(layer "F.Fab")
		)
		(fp_line
			(start 0.12065 -0.2794)
			(end 0.12065 -0.3048)
			(stroke
				(width 0.1)
				(type default)
			)
			(layer "F.Fab")
		)
		(fp_line
			(start 0.67945 -0.3048)
			(end 0.67945 0.3048)
			(stroke
				(width 0.1)
				(type default)
			)
			(layer "F.Fab")
		)
		(fp_line
			(start 0.67945 0.3048)
			(end 0.120396 0.3048)
			(stroke
				(width 0.1)
				(type default)
			)
			(layer "F.Fab")
		)
		(pad "1" smd circle
			(at -0.40005 0)
			(size 0 0)
			(layers "F.Cu" "F.Mask" "F.Paste")
			(net "P12V_NIC5_R")
		)
		(pad "2" smd circle
			(at 0.40005 0)
			(size 0 0)
			(layers "F.Cu" "F.Mask" "F.Paste")
			(net "GND")
		)
	)
	(footprint ""
		(layer "F.Cu")
		(at 25.358344 -250.070874 -90)
		(property "Reference" "R1159"
			(at 0 0 270)
			(layer "F.SilkS")
			(hide yes)
			(effects
				(font
					(size 1.27 1.27)
				)
			)
		)
		(property "Value" ""
			(at 0 0 270)
			(layer "F.Fab")
			(effects
				(font
					(size 1.27 1.27)
				)
			)
		)
		(duplicate_pad_numbers_are_jumpers no)
		(fp_line
			(start -0.7874 0.4064)
			(end -0.7874 -0.4064)
			(stroke
				(width 0.1524)
				(type default)
			)
			(layer "F.SilkS")
		)
		(fp_line
			(start 0.7874 0.4064)
			(end -0.7874 0.4064)
			(stroke
				(width 0.1524)
				(type default)
			)
			(layer "F.SilkS")
		)
		(fp_line
			(start -0.7874 -0.4064)
			(end 0.7874 -0.4064)
			(stroke
				(width 0.1524)
				(type default)
			)
			(layer "F.SilkS")
		)
		(fp_line
			(start 0.7874 -0.4064)
			(end 0.7874 0.4064)
			(stroke
				(width 0.1524)
				(type default)
			)
			(layer "F.SilkS")
		)
		(fp_line
			(start -0.67945 0.3048)
			(end -0.67945 -0.305054)
			(stroke
				(width 0.1)
				(type default)
			)
			(layer "F.Fab")
		)
		(fp_line
			(start -0.12065 0.3048)
			(end -0.67945 0.3048)
			(stroke
				(width 0.1)
				(type default)
			)
			(layer "F.Fab")
		)
		(fp_line
			(start 0.120396 0.3048)
			(end 0.120396 0.2794)
			(stroke
				(width 0.1)
				(type default)
			)
			(layer "F.Fab")
		)
		(fp_line
			(start 0.67945 0.3048)
			(end 0.120396 0.3048)
			(stroke
				(width 0.1)
				(type default)
			)
			(layer "F.Fab")
		)
		(fp_line
			(start -0.12065 0.2794)
			(end -0.12065 0.3048)
			(stroke
				(width 0.1)
				(type default)
			)
			(layer "F.Fab")
		)
		(fp_line
			(start 0.120396 0.2794)
			(end -0.12065 0.2794)
			(stroke
				(width 0.1)
				(type default)
			)
			(layer "F.Fab")
		)
		(fp_line
			(start -0.12065 -0.2794)
			(end 0.12065 -0.2794)
			(stroke
				(width 0.1)
				(type default)
			)
			(layer "F.Fab")
		)
		(fp_line
			(start 0.12065 -0.2794)
			(end 0.12065 -0.3048)
			(stroke
				(width 0.1)
				(type default)
			)
			(layer "F.Fab")
		)
		(fp_line
			(start 0.12065 -0.3048)
			(end 0.67945 -0.3048)
			(stroke
				(width 0.1)
				(type default)
			)
			(layer "F.Fab")
		)
		(fp_line
			(start 0.67945 -0.3048)
			(end 0.67945 0.3048)
			(stroke
				(width 0.1)
				(type default)
			)
			(layer "F.Fab")
		)
		(fp_line
			(start -0.67945 -0.305054)
			(end -0.12065 -0.305054)
			(stroke
				(width 0.1)
				(type default)
			)
			(layer "F.Fab")
		)
		(fp_line
			(start -0.12065 -0.305054)
			(end -0.12065 -0.2794)
			(stroke
				(width 0.1)
				(type default)
			)
			(layer "F.Fab")
		)
		(pad "1" smd circle
			(at -0.40005 0 270)
			(size 0 0)
			(layers "F.Cu" "F.Mask" "F.Paste")
			(net "PEX0_MODE_SEL7")
		)
		(pad "2" smd circle
			(at 0.40005 0 270)
			(size 0 0)
			(layers "F.Cu" "F.Mask" "F.Paste")
			(net "P1V8_PEX")
		)
	)
	(footprint ""
		(layer "F.Cu")
		(at 181.728872 -350.098614 90)
		(property "Reference" "C2531"
			(at 0 0 90)
			(layer "F.SilkS")
			(hide yes)
			(effects
				(font
					(size 1.27 1.27)
				)
			)
		)
		(property "Value" ""
			(at 0 0 90)
			(layer "F.Fab")
			(effects
				(font
					(size 1.27 1.27)
				)
			)
		)
		(duplicate_pad_numbers_are_jumpers no)
		(fp_line
			(start 0.299974 -0.150114)
			(end 0.299974 0.150114)
			(stroke
				(width 0.1)
				(type default)
			)
			(layer "F.Fab")
		)
		(fp_line
			(start -0.299974 -0.150114)
			(end 0.299974 -0.150114)
			(stroke
				(width 0.1)
				(type default)
			)
			(layer "F.Fab")
		)
		(fp_line
			(start 0.299974 0.150114)
			(end -0.299974 0.150114)
			(stroke
				(width 0.1)
				(type default)
			)
			(layer "F.Fab")
		)
		(fp_line
			(start -0.299974 0.150114)
			(end -0.299974 -0.150114)
			(stroke
				(width 0.1)
				(type default)
			)
			(layer "F.Fab")
		)
		(pad "1" smd rect
			(at -0.2667 0 90)
			(size 0.3048 0.381)
			(layers "F.Cu" "F.Mask" "F.Paste")
			(net "P5E_PEX1_STN4_TX_DN<70>")
		)
		(pad "2" smd rect
			(at 0.2667 0 90)
			(size 0.3048 0.381)
			(layers "F.Cu" "F.Mask" "F.Paste")
			(net "P5E_PEX1_STN4_TX_C_DN<70>")
		)
	)
	(footprint ""
		(layer "F.Cu")
		(at 130.26263 -94.16542)
		(property "Reference" "U124"
			(at -2.1844 -4.587748 0)
			(unlocked yes)
			(layer "F.SilkS")
			(effects
				(font
					(size 0.7874 0.5842)
					(thickness 0.1524)
				)
				(justify left)
			)
		)
		(property "Value" ""
			(at 0 0 0)
			(layer "F.Fab")
			(effects
				(font
					(size 1.27 1.27)
				)
			)
		)
		(duplicate_pad_numbers_are_jumpers no)
		(fp_line
			(start -1.8542 -3.949954)
			(end -1.8542 3.949954)
			(stroke
				(width 0.1524)
				(type default)
			)
			(layer "F.SilkS")
		)
		(fp_line
			(start -1.8542 3.949954)
			(end 1.8542 3.949954)
			(stroke
				(width 0.1524)
				(type default)
			)
			(layer "F.SilkS")
		)
		(fp_line
			(start -1.282954 -3.949954)
			(end -1.8542 -3.949954)
			(stroke
				(width 0.1524)
				(type default)
			)
			(layer "F.SilkS")
		)
		(fp_line
			(start 0 -2.667)
			(end -1.282954 -3.949954)
			(stroke
				(width 0.1524)
				(type default)
			)
			(layer "F.SilkS")
		)
		(fp_line
			(start 1.282954 -3.949954)
			(end 0 -2.667)
			(stroke
				(width 0.1524)
				(type default)
			)
			(layer "F.SilkS")
		)
		(fp_line
			(start 1.8542 -3.949954)
			(end 1.282954 -3.949954)
			(stroke
				(width 0.1524)
				(type default)
			)
			(layer "F.SilkS")
		)
		(fp_line
			(start 1.8542 3.949954)
			(end 1.8542 -3.949954)
			(stroke
				(width 0.1524)
				(type default)
			)
			(layer "F.SilkS")
		)
		(fp_poly
			(pts
				(xy -4.8006 -4.08305) (xy -4.8006 -3.06705) (xy -3.7846 -3.57505)
			)
			(stroke
				(width 0)
				(type default)
			)
			(fill yes)
			(layer "F.SilkS")
		)
		(fp_line
			(start -2.249932 -3.949954)
			(end -2.249932 3.949954)
			(stroke
				(width 0.1)
				(type default)
			)
			(layer "F.Fab")
		)
		(fp_line
			(start -2.249932 3.949954)
			(end 2.249932 3.949954)
			(stroke
				(width 0.1)
				(type default)
			)
			(layer "F.Fab")
		)
		(fp_line
			(start 2.249932 -3.949954)
			(end -2.249932 -3.949954)
			(stroke
				(width 0.1)
				(type default)
			)
			(layer "F.Fab")
		)
		(fp_line
			(start 2.249932 3.949954)
			(end 2.249932 -3.949954)
			(stroke
				(width 0.1)
				(type default)
			)
			(layer "F.Fab")
		)
		(fp_poly
			(pts
				(xy -4.8006 -4.08305) (xy -4.8006 -3.06705) (xy -3.7846 -3.57505)
			)
			(stroke
				(width 0)
				(type default)
			)
			(fill yes)
			(layer "F.Fab")
		)
		(pad "1" smd rect
			(at -2.800096 -3.57505 270)
			(size 0.3048 1.6002)
			(layers "F.Cu" "F.Mask" "F.Paste")
			(net "BIC_I2C9_SSD_MUX0_A0")
		)
		(pad "2" smd rect
			(at -2.800096 -2.925064 270)
			(size 0.3048 1.6002)
			(layers "F.Cu" "F.Mask" "F.Paste")
			(net "BIC_I2C9_SSD_MUX0_A1")
		)
		(pad "3" smd rect
			(at -2.800096 -2.275078 270)
			(size 0.3048 1.6002)
			(layers "F.Cu" "F.Mask" "F.Paste")
			(net "RST_BIC_I2C9_SSD_MUX0_R_N")
		)
		(pad "4" smd rect
			(at -2.800096 -1.625092 270)
			(size 0.3048 1.6002)
			(layers "F.Cu" "F.Mask" "F.Paste")
			(net "SMB_BIC_I2C9_MUX0_SSD0_SDA")
		)
		(pad "5" smd rect
			(at -2.800096 -0.975106 270)
			(size 0.3048 1.6002)
			(layers "F.Cu" "F.Mask" "F.Paste")
			(net "SMB_BIC_I2C9_MUX0_SSD0_SCL")
		)
		(pad "6" smd rect
			(at -2.800096 -0.32512 270)
			(size 0.3048 1.6002)
			(layers "F.Cu" "F.Mask" "F.Paste")
			(net "SMB_BIC_I2C9_MUX0_SSD1_SDA")
		)
		(pad "7" smd rect
			(at -2.800096 0.32512 270)
			(size 0.3048 1.6002)
			(layers "F.Cu" "F.Mask" "F.Paste")
			(net "SMB_BIC_I2C9_MUX0_SSD1_SCL")
		)
		(pad "8" smd rect
			(at -2.800096 0.975106 270)
			(size 0.3048 1.6002)
			(layers "F.Cu" "F.Mask" "F.Paste")
			(net "SMB_BIC_I2C9_MUX0_SSD2_SDA")
		)
		(pad "9" smd rect
			(at -2.800096 1.625092 270)
			(size 0.3048 1.6002)
			(layers "F.Cu" "F.Mask" "F.Paste")
			(net "SMB_BIC_I2C9_MUX0_SSD2_SCL")
		)
		(pad "10" smd rect
			(at -2.800096 2.275078 270)
			(size 0.3048 1.6002)
			(layers "F.Cu" "F.Mask" "F.Paste")
			(net "SMB_BIC_I2C9_MUX0_SSD3_SDA")
		)
		(pad "11" smd rect
			(at -2.800096 2.925064 270)
			(size 0.3048 1.6002)
			(layers "F.Cu" "F.Mask" "F.Paste")
			(net "SMB_BIC_I2C9_MUX0_SSD3_SCL")
		)
		(pad "12" smd rect
			(at -2.800096 3.57505 270)
			(size 0.3048 1.6002)
			(layers "F.Cu" "F.Mask" "F.Paste")
			(net "GND")
		)
		(pad "13" smd rect
			(at 2.800096 3.57505 270)
			(size 0.3048 1.6002)
			(layers "F.Cu" "F.Mask" "F.Paste")
			(net "SMB_BIC_I2C9_MUX0_SSD4_SDA")
		)
		(pad "14" smd rect
			(at 2.800096 2.925064 270)
			(size 0.3048 1.6002)
			(layers "F.Cu" "F.Mask" "F.Paste")
			(net "SMB_BIC_I2C9_MUX0_SSD4_SCL")
		)
		(pad "15" smd rect
			(at 2.800096 2.275078 270)
			(size 0.3048 1.6002)
			(layers "F.Cu" "F.Mask" "F.Paste")
			(net "SMB_BIC_I2C9_MUX0_SSD5_SDA")
		)
		(pad "16" smd rect
			(at 2.800096 1.625092 270)
			(size 0.3048 1.6002)
			(layers "F.Cu" "F.Mask" "F.Paste")
			(net "SMB_BIC_I2C9_MUX0_SSD5_SCL")
		)
		(pad "17" smd rect
			(at 2.800096 0.975106 270)
			(size 0.3048 1.6002)
			(layers "F.Cu" "F.Mask" "F.Paste")
			(net "SMB_BIC_I2C9_MUX0_SSD6_SDA")
		)
		(pad "18" smd rect
			(at 2.800096 0.32512 270)
			(size 0.3048 1.6002)
			(layers "F.Cu" "F.Mask" "F.Paste")
			(net "SMB_BIC_I2C9_MUX0_SSD6_SCL")
		)
		(pad "19" smd rect
			(at 2.800096 -0.32512 270)
			(size 0.3048 1.6002)
			(layers "F.Cu" "F.Mask" "F.Paste")
			(net "SMB_BIC_I2C9_MUX0_SSD7_SDA")
		)
		(pad "20" smd rect
			(at 2.800096 -0.975106 270)
			(size 0.3048 1.6002)
			(layers "F.Cu" "F.Mask" "F.Paste")
			(net "SMB_BIC_I2C9_MUX0_SSD7_SCL")
		)
		(pad "21" smd rect
			(at 2.800096 -1.625092 270)
			(size 0.3048 1.6002)
			(layers "F.Cu" "F.Mask" "F.Paste")
			(net "BIC_I2C9_SSD_MUX0_A2")
		)
		(pad "22" smd rect
			(at 2.800096 -2.275078 270)
			(size 0.3048 1.6002)
			(layers "F.Cu" "F.Mask" "F.Paste")
			(net "SMB_BIC_I2C9_SSD_MUX0_SCL")
		)
		(pad "23" smd rect
			(at 2.800096 -2.925064 270)
			(size 0.3048 1.6002)
			(layers "F.Cu" "F.Mask" "F.Paste")
			(net "SMB_BIC_I2C9_SSD_MUX0_SDA")
		)
		(pad "24" smd rect
			(at 2.800096 -3.57505 270)
			(size 0.3048 1.6002)
			(layers "F.Cu" "F.Mask" "F.Paste")
			(net "P3V3_AUX")
		)
	)
	(footprint ""
		(layer "F.Cu")
		(at 139.724892 -259.378958)
		(property "Reference" "R1328"
			(at 0 0 0)
			(layer "F.SilkS")
			(hide yes)
			(effects
				(font
					(size 1.27 1.27)
				)
			)
		)
		(property "Value" ""
			(at 0 0 0)
			(layer "F.Fab")
			(effects
				(font
					(size 1.27 1.27)
				)
			)
		)
		(duplicate_pad_numbers_are_jumpers no)
		(fp_line
			(start -0.7874 -0.4064)
			(end 0.7874 -0.4064)
			(stroke
				(width 0.1524)
				(type default)
			)
			(layer "F.SilkS")
		)
		(fp_line
			(start -0.7874 0.4064)
			(end -0.7874 -0.4064)
			(stroke
				(width 0.1524)
				(type default)
			)
			(layer "F.SilkS")
		)
		(fp_line
			(start 0.7874 -0.4064)
			(end 0.7874 0.4064)
			(stroke
				(width 0.1524)
				(type default)
			)
			(layer "F.SilkS")
		)
		(fp_line
			(start 0.7874 0.4064)
			(end -0.7874 0.4064)
			(stroke
				(width 0.1524)
				(type default)
			)
			(layer "F.SilkS")
		)
		(fp_line
			(start -0.67945 -0.305054)
			(end -0.12065 -0.305054)
			(stroke
				(width 0.1)
				(type default)
			)
			(layer "F.Fab")
		)
		(fp_line
			(start -0.67945 0.3048)
			(end -0.67945 -0.305054)
			(stroke
				(width 0.1)
				(type default)
			)
			(layer "F.Fab")
		)
		(fp_line
			(start -0.12065 -0.305054)
			(end -0.12065 -0.2794)
			(stroke
				(width 0.1)
				(type default)
			)
			(layer "F.Fab")
		)
		(fp_line
			(start -0.12065 -0.2794)
			(end 0.12065 -0.2794)
			(stroke
				(width 0.1)
				(type default)
			)
			(layer "F.Fab")
		)
		(fp_line
			(start -0.12065 0.2794)
			(end -0.12065 0.3048)
			(stroke
				(width 0.1)
				(type default)
			)
			(layer "F.Fab")
		)
		(fp_line
			(start -0.12065 0.3048)
			(end -0.67945 0.3048)
			(stroke
				(width 0.1)
				(type default)
			)
			(layer "F.Fab")
		)
		(fp_line
			(start 0.120396 0.2794)
			(end -0.12065 0.2794)
			(stroke
				(width 0.1)
				(type default)
			)
			(layer "F.Fab")
		)
		(fp_line
			(start 0.120396 0.3048)
			(end 0.120396 0.2794)
			(stroke
				(width 0.1)
				(type default)
			)
			(layer "F.Fab")
		)
		(fp_line
			(start 0.12065 -0.3048)
			(end 0.67945 -0.3048)
			(stroke
				(width 0.1)
				(type default)
			)
			(layer "F.Fab")
		)
		(fp_line
			(start 0.12065 -0.2794)
			(end 0.12065 -0.3048)
			(stroke
				(width 0.1)
				(type default)
			)
			(layer "F.Fab")
		)
		(fp_line
			(start 0.67945 -0.3048)
			(end 0.67945 0.3048)
			(stroke
				(width 0.1)
				(type default)
			)
			(layer "F.Fab")
		)
		(fp_line
			(start 0.67945 0.3048)
			(end 0.120396 0.3048)
			(stroke
				(width 0.1)
				(type default)
			)
			(layer "F.Fab")
		)
		(pad "1" smd circle
			(at -0.40005 0)
			(size 0 0)
			(layers "F.Cu" "F.Mask" "F.Paste")
			(net "PEX1_SYS_ERR_N_G")
		)
		(pad "2" smd circle
			(at 0.40005 0)
			(size 0 0)
			(layers "F.Cu" "F.Mask" "F.Paste")
			(net "P3V3_AUX")
		)
	)
)
